# S9S_MB_2U (Grand Teton) — schematic netlist excerpt (pin names and nets, part order shuffled) for the footprints in the layout excerpt that follows; sources: Cadence DE-HDL packaged netlist, KiCad conversion of 03242023_DA0F0TMBIJ0_F0T_Motherboard_J_brd_V01_OCP.brd

R157  Q_RES  100 1% CHIP  pkg 0402LF  page 125 : A = RST_CPU1_BUF_R_N ; B = PVNN_TERM_CPU1
C1234  Q_CAP  0.1UF 25V 10% X7R  pkg 0402  page 153 : A = P12V_OCP_SFF ; B = GND

(kicad_pcb
	(version 20260206)
	(generator "pcbnew")
	(generator_version "10.0")
	(general
		(thickness 1.6)
		(legacy_teardrops no)
	)
	(paper "A4")
	(title_block
		(title "03242023_DA0F0TMBIJ0_F0T_Motherboard_J_brd_V01_OCP.brd")
		(comment 1 "Grand Teton / footprints 4597-4598 of 6105")
	)
	(layers
		(0 "F.Cu" signal "TOP")
		(4 "In1.Cu" signal "GND")
		(6 "In2.Cu" signal "IN1")
		(8 "In3.Cu" signal "GND1")
		(10 "In4.Cu" signal "IN2")
		(12 "In5.Cu" signal "GND2")
		(14 "In6.Cu" signal "IN3")
		(16 "In7.Cu" signal "GND3")
		(18 "In8.Cu" signal "VCC")
		(20 "In9.Cu" signal "VCC1")
		(22 "In10.Cu" signal "GND4")
		(24 "In11.Cu" signal "IN4")
		(26 "In12.Cu" signal "GND5")
		(28 "In13.Cu" signal "IN5")
		(30 "In14.Cu" signal "GND6")
		(32 "In15.Cu" signal "IN6")
		(34 "In16.Cu" signal "GND7")
		(2 "B.Cu" signal "BOTTOM")
		(9 "F.Adhes" user "F.Adhesive")
		(11 "B.Adhes" user "B.Adhesive")
		(13 "F.Paste" user "Package Geometry/Pastemask Top")
		(15 "B.Paste" user "Package Geometry/Pastemask Bottom")
		(5 "F.SilkS" user "Ref Des/Silkscreen Top")
		(7 "B.SilkS" user "Ref Des/Silkscreen Bottom")
		(1 "F.Mask" user "Board Geometry/Soldermask Top")
		(3 "B.Mask" user "Board Geometry/Soldermask Bottom")
		(17 "Dwgs.User" user "User.Drawings")
		(19 "Cmts.User" user "User.Comments")
		(21 "Eco1.User" user "User.Eco1")
		(23 "Eco2.User" user "User.Eco2")
		(25 "Edge.Cuts" user "Board Geometry/Outline")
		(27 "Margin" user)
		(31 "F.CrtYd" user "Package Geometry/Place Bound Top")
		(29 "B.CrtYd" user "Package Geometry/Place Bound Bottom")
		(35 "F.Fab" user "Ref Des/Assembly Top")
		(33 "B.Fab" user "Ref Des/Assembly Bottom")
	)
	(footprint ""
		(layer "B.Cu")
		(at 55.695088 -193.39179 90)
		(property "Reference" "R157"
			(at 0 0 90)
			(layer "B.SilkS")
			(hide yes)
			(effects
				(font
					(size 1.27 1.27)
				)
				(justify mirror)
			)
		)
		(property "Value" ""
			(at 0 0 90)
			(layer "B.Fab")
			(effects
				(font
					(size 1.27 1.27)
				)
				(justify mirror)
			)
		)
		(duplicate_pad_numbers_are_jumpers no)
		(fp_line
			(start 0.7874 -0.4064)
			(end -0.7874 -0.4064)
			(stroke
				(width 0.1524)
				(type default)
			)
			(layer "B.SilkS")
		)
		(fp_line
			(start -0.7874 -0.4064)
			(end -0.7874 0.4064)
			(stroke
				(width 0.1524)
				(type default)
			)
			(layer "B.SilkS")
		)
		(fp_line
			(start 0.7874 0.4064)
			(end 0.7874 -0.4064)
			(stroke
				(width 0.1524)
				(type default)
			)
			(layer "B.SilkS")
		)
		(fp_line
			(start -0.7874 0.4064)
			(end 0.7874 0.4064)
			(stroke
				(width 0.1524)
				(type default)
			)
			(layer "B.SilkS")
		)
		(fp_line
			(start 0.67945 -0.305054)
			(end 0.12065 -0.305054)
			(stroke
				(width 0.1)
				(type default)
			)
			(layer "B.Fab")
		)
		(fp_line
			(start 0.12065 -0.305054)
			(end 0.12065 -0.2794)
			(stroke
				(width 0.1)
				(type default)
			)
			(layer "B.Fab")
		)
		(fp_line
			(start -0.12065 -0.3048)
			(end -0.67945 -0.3048)
			(stroke
				(width 0.1)
				(type default)
			)
			(layer "B.Fab")
		)
		(fp_line
			(start -0.67945 -0.3048)
			(end -0.67945 0.3048)
			(stroke
				(width 0.1)
				(type default)
			)
			(layer "B.Fab")
		)
		(fp_line
			(start 0.12065 -0.2794)
			(end -0.12065 -0.2794)
			(stroke
				(width 0.1)
				(type default)
			)
			(layer "B.Fab")
		)
		(fp_line
			(start -0.12065 -0.2794)
			(end -0.12065 -0.3048)
			(stroke
				(width 0.1)
				(type default)
			)
			(layer "B.Fab")
		)
		(fp_line
			(start 0.12065 0.2794)
			(end 0.12065 0.3048)
			(stroke
				(width 0.1)
				(type default)
			)
			(layer "B.Fab")
		)
		(fp_line
			(start -0.120396 0.2794)
			(end 0.12065 0.2794)
			(stroke
				(width 0.1)
				(type default)
			)
			(layer "B.Fab")
		)
		(fp_line
			(start 0.67945 0.3048)
			(end 0.67945 -0.305054)
			(stroke
				(width 0.1)
				(type default)
			)
			(layer "B.Fab")
		)
		(fp_line
			(start 0.12065 0.3048)
			(end 0.67945 0.3048)
			(stroke
				(width 0.1)
				(type default)
			)
			(layer "B.Fab")
		)
		(fp_line
			(start -0.120396 0.3048)
			(end -0.120396 0.2794)
			(stroke
				(width 0.1)
				(type default)
			)
			(layer "B.Fab")
		)
		(fp_line
			(start -0.67945 0.3048)
			(end -0.120396 0.3048)
			(stroke
				(width 0.1)
				(type default)
			)
			(layer "B.Fab")
		)
		(pad "1" smd circle
			(at 0.40005 0 270)
			(size 0 0)
			(layers "B.Cu" "B.Mask" "B.Paste")
			(net "RST_CPU1_BUF_R_N")
		)
		(pad "2" smd circle
			(at -0.40005 0 270)
			(size 0 0)
			(layers "B.Cu" "B.Mask" "B.Paste")
			(net "PVNN_TERM_CPU1")
		)
	)
	(footprint ""
		(layer "B.Cu")
		(at 440.383676 -15.656306)
		(property "Reference" "C1234"
			(at 0 0 0)
			(layer "B.SilkS")
			(hide yes)
			(effects
				(font
					(size 1.27 1.27)
				)
				(justify mirror)
			)
		)
		(property "Value" ""
			(at 0 0 0)
			(layer "B.Fab")
			(effects
				(font
					(size 1.27 1.27)
				)
				(justify mirror)
			)
		)
		(duplicate_pad_numbers_are_jumpers no)
		(fp_line
			(start -0.7874 -0.4064)
			(end -0.7874 0.4064)
			(stroke
				(width 0.1524)
				(type default)
			)
			(layer "B.SilkS")
		)
		(fp_line
			(start -0.7874 0.4064)
			(end 0.7874 0.4064)
			(stroke
				(width 0.1524)
				(type default)
			)
			(layer "B.SilkS")
		)
		(fp_line
			(start 0.7874 -0.4064)
			(end -0.7874 -0.4064)
			(stroke
				(width 0.1524)
				(type default)
			)
			(layer "B.SilkS")
		)
		(fp_line
			(start 0.7874 0.4064)
			(end 0.7874 -0.4064)
			(stroke
				(width 0.1524)
				(type default)
			)
			(layer "B.SilkS")
		)
		(fp_line
			(start -0.67945 -0.3048)
			(end -0.67945 0.3048)
			(stroke
				(width 0.1)
				(type default)
			)
			(layer "B.Fab")
		)
		(fp_line
			(start -0.67945 0.3048)
			(end -0.120396 0.3048)
			(stroke
				(width 0.1)
				(type default)
			)
			(layer "B.Fab")
		)
		(fp_line
			(start -0.12065 -0.3048)
			(end -0.67945 -0.3048)
			(stroke
				(width 0.1)
				(type default)
			)
			(layer "B.Fab")
		)
		(fp_line
			(start -0.12065 -0.2794)
			(end -0.12065 -0.3048)
			(stroke
				(width 0.1)
				(type default)
			)
			(layer "B.Fab")
		)
		(fp_line
			(start -0.120396 0.2794)
			(end 0.12065 0.2794)
			(stroke
				(width 0.1)
				(type default)
			)
			(layer "B.Fab")
		)
		(fp_line
			(start -0.120396 0.3048)
			(end -0.120396 0.2794)
			(stroke
				(width 0.1)
				(type default)
			)
			(layer "B.Fab")
		)
		(fp_line
			(start 0.12065 -0.305054)
			(end 0.12065 -0.2794)
			(stroke
				(width 0.1)
				(type default)
			)
			(layer "B.Fab")
		)
		(fp_line
			(start 0.12065 -0.2794)
			(end -0.12065 -0.2794)
			(stroke
				(width 0.1)
				(type default)
			)
			(layer "B.Fab")
		)
		(fp_line
			(start 0.12065 0.2794)
			(end 0.12065 0.3048)
			(stroke
				(width 0.1)
				(type default)
			)
			(layer "B.Fab")
		)
		(fp_line
			(start 0.12065 0.3048)
			(end 0.67945 0.3048)
			(stroke
				(width 0.1)
				(type default)
			)
			(layer "B.Fab")
		)
		(fp_line
			(start 0.67945 -0.305054)
			(end 0.12065 -0.305054)
			(stroke
				(width 0.1)
				(type default)
			)
			(layer "B.Fab")
		)
		(fp_line
			(start 0.67945 0.3048)
			(end 0.67945 -0.305054)
			(stroke
				(width 0.1)
				(type default)
			)
			(layer "B.Fab")
		)
		(pad "1" smd circle
			(at 0.40005 0 180)
			(size 0 0)
			(layers "B.Cu" "B.Mask" "B.Paste")
			(net "P12V_OCP_SFF")
		)
		(pad "2" smd circle
			(at -0.40005 0 180)
			(size 0 0)
			(layers "B.Cu" "B.Mask" "B.Paste")
			(net "GND")
		)
	)
)
